(kicad_pcb
	(version 20241229)
	(generator "pcbnew")
	(generator_version "9.0")
	(general
		(thickness 1.62)
		(legacy_teardrops no)
	)
	(paper "A4")
	(title_block
		(title "OCuLink to 10GbE adapter")
		(date "2026-02-23")
		(rev "1.1.0")
		(company "Antmicro Ltd")
		(comment 1 "www.antmicro.com")
		(comment 9 "footprints 419-423 of 510")
	)
	(layers
		(0 "F.Cu" signal)
		(4 "In1.Cu" signal)
		(6 "In2.Cu" signal)
		(8 "In3.Cu" signal)
		(10 "In4.Cu" signal)
		(12 "In5.Cu" signal)
		(14 "In6.Cu" signal)
		(2 "B.Cu" signal)
		(9 "F.Adhes" user "F.Adhesive")
		(11 "B.Adhes" user "B.Adhesive")
		(13 "F.Paste" user)
		(15 "B.Paste" user)
		(5 "F.SilkS" user "F.Silkscreen")
		(7 "B.SilkS" user "B.Silkscreen")
		(1 "F.Mask" user)
		(3 "B.Mask" user)
		(17 "Dwgs.User" user "User.Drawings")
		(19 "Cmts.User" user "User.Comments")
		(21 "Eco1.User" user "User.Eco1")
		(23 "Eco2.User" user "User.Eco2")
		(25 "Edge.Cuts" user)
		(27 "Margin" user)
		(31 "F.CrtYd" user "F.Courtyard")
		(29 "B.CrtYd" user "B.Courtyard")
		(35 "F.Fab" user)
		(33 "B.Fab" user)
	)
	(footprint "antmicro-footprints:R_0402_1005Metric"
		(layer "B.Cu")
		(at 109.49 88.86 90)
		(descr "Resistor SMD 0402")
		(tags "resistor SMD 0402")
		(property "Reference" "R131"
			(at -3.58 -0.38 90)
			(layer "B.SilkS")
			(effects
				(font
					(size 0.7 0.7)
					(thickness 0.15)
				)
				(justify right top mirror)
			)
		)
		(property "Value" "R_10k_0402"
			(at -1.011843 -1.772046 90)
			(layer "B.Fab")
			(hide yes)
			(effects
				(font
					(size 0.7 0.7)
					(thickness 0.15)
				)
				(justify right top mirror)
			)
		)
		(property "Datasheet" "https://www.bourns.com/docs/product-datasheets/cr.pdf"
			(at 0 0 90)
			(layer "B.Fab")
			(hide yes)
			(effects
				(font
					(size 1.27 1.27)
					(thickness 0.15)
				)
				(justify mirror)
			)
		)
		(property "Description" "SMD Chip Resistor, 10 kohm, ± 1%, 62.5 mW, 0402 [1005 Metric], Thick Film, General Purpose"
			(at 0 0 90)
			(layer "B.Fab")
			(hide yes)
			(effects
				(font
					(size 1.27 1.27)
					(thickness 0.15)
				)
				(justify mirror)
			)
		)
		(property "MPN" "CR0402-FX-1002GLF"
			(at 0 0 90)
			(unlocked yes)
			(layer "B.Fab")
			(hide yes)
			(effects
				(font
					(size 1 1)
					(thickness 0.15)
				)
				(justify mirror)
			)
		)
		(property "Manufacturer" "Bourns"
			(at 0 0 90)
			(unlocked yes)
			(layer "B.Fab")
			(hide yes)
			(effects
				(font
					(size 1 1)
					(thickness 0.15)
				)
				(justify mirror)
			)
		)
		(property "License" "Apache-2.0"
			(at 0 0 90)
			(unlocked yes)
			(layer "B.Fab")
			(hide yes)
			(effects
				(font
					(size 1 1)
					(thickness 0.15)
				)
				(justify mirror)
			)
		)
		(property "Author" "Antmicro"
			(at 0 0 90)
			(unlocked yes)
			(layer "B.Fab")
			(hide yes)
			(effects
				(font
					(size 1 1)
					(thickness 0.15)
				)
				(justify mirror)
			)
		)
		(property "Val" "10k"
			(at 0 0 90)
			(unlocked yes)
			(layer "B.Fab")
			(hide yes)
			(effects
				(font
					(size 1 1)
					(thickness 0.15)
				)
				(justify mirror)
			)
		)
		(property "Tolerance" "1%"
			(at 0 0 90)
			(unlocked yes)
			(layer "B.Fab")
			(hide yes)
			(effects
				(font
					(size 1 1)
					(thickness 0.15)
				)
				(justify mirror)
			)
		)
		(sheetname "/X710-AT2 RSVD/")
		(sheetfile "x710-at2-rsvd.kicad_sch")
		(attr smd)
		(fp_rect
			(start -0.925 0.47)
			(end 0.925 -0.47)
			(stroke
				(width 0.05)
				(type default)
			)
			(fill no)
			(layer "B.CrtYd")
		)
		(fp_rect
			(start -0.5 0.25)
			(end 0.5 -0.25)
			(stroke
				(width 0.15)
				(type solid)
			)
			(fill no)
			(layer "B.Fab")
		)
		(pad "1" smd roundrect
			(at -0.48 0 90)
			(size 0.59 0.64)
			(layers "B.Cu" "B.Mask" "B.Paste")
			(roundrect_rratio 0.25)
			(net 28 "GND")
			(pintype "passive")
		)
		(pad "2" smd roundrect
			(at 0.48 0 90)
			(size 0.59 0.64)
			(layers "B.Cu" "B.Mask" "B.Paste")
			(roundrect_rratio 0.25)
			(net 119 "/X710-AT2 RSVD/DEBUG_Y20")
			(pintype "passive")
		)
	)
	(footprint "antmicro-footprints:C_0402_1005Metric"
		(layer "B.Cu")
		(at 66 131.4)
		(descr "Capacitor SMD 0402")
		(tags "capacitor SMD 0402")
		(property "Reference" "C56"
			(at -3 -0.3 0)
			(layer "B.SilkS")
			(effects
				(font
					(size 0.7 0.7)
					(thickness 0.15)
				)
				(justify right top mirror)
			)
		)
		(property "Value" "C_1u_25V_0402"
			(at -1.022927 -2.155213 0)
			(layer "B.Fab")
			(hide yes)
			(effects
				(font
					(size 0.7 0.7)
					(thickness 0.15)
				)
				(justify right top mirror)
			)
		)
		(property "Datasheet" "https://www.murata.com/products/productdetail?partno=GRM155R61E105KE11%23"
			(at 0 0 0)
			(layer "B.Fab")
			(hide yes)
			(effects
				(font
					(size 1.27 1.27)
					(thickness 0.15)
				)
				(justify mirror)
			)
		)
		(property "Description" "SMD Multilayer Ceramic Capacitor, 1 µF, 25 V, 0402 [1005 Metric], ± 10%, X5R, GRM Series"
			(at 0 0 0)
			(layer "B.Fab")
			(hide yes)
			(effects
				(font
					(size 1.27 1.27)
					(thickness 0.15)
				)
				(justify mirror)
			)
		)
		(property "MPN" "GRM155R61E105KE11J"
			(at 0 0 0)
			(unlocked yes)
			(layer "B.Fab")
			(hide yes)
			(effects
				(font
					(size 1 1)
					(thickness 0.15)
				)
				(justify mirror)
			)
		)
		(property "Manufacturer" "Murata"
			(at 0 0 0)
			(unlocked yes)
			(layer "B.Fab")
			(hide yes)
			(effects
				(font
					(size 1 1)
					(thickness 0.15)
				)
				(justify mirror)
			)
		)
		(property "License" "Apache-2.0"
			(at 0 0 0)
			(unlocked yes)
			(layer "B.Fab")
			(hide yes)
			(effects
				(font
					(size 1 1)
					(thickness 0.15)
				)
				(justify mirror)
			)
		)
		(property "Author" "Antmicro"
			(at 0 0 0)
			(unlocked yes)
			(layer "B.Fab")
			(hide yes)
			(effects
				(font
					(size 1 1)
					(thickness 0.15)
				)
				(justify mirror)
			)
		)
		(property "Val" "1u"
			(at 0 0 0)
			(unlocked yes)
			(layer "B.Fab")
			(hide yes)
			(effects
				(font
					(size 1 1)
					(thickness 0.15)
				)
				(justify mirror)
			)
		)
		(property "Voltage" "25V"
			(at 0 0 0)
			(unlocked yes)
			(layer "B.Fab")
			(hide yes)
			(effects
				(font
					(size 1 1)
					(thickness 0.15)
				)
				(justify mirror)
			)
		)
		(property "Dielectric" "X5R"
			(at 0 0 0)
			(unlocked yes)
			(layer "B.Fab")
			(hide yes)
			(effects
				(font
					(size 1 1)
					(thickness 0.15)
				)
				(justify mirror)
			)
		)
		(sheetname "/2xRJ45/")
		(sheetfile "2xrj45.kicad_sch")
		(attr smd)
		(fp_rect
			(start -0.925 0.47)
			(end 0.925 -0.47)
			(stroke
				(width 0.05)
				(type default)
			)
			(fill no)
			(layer "B.CrtYd")
		)
		(fp_line
			(start -0.494 -0.248)
			(end -0.494 0.25)
			(stroke
				(width 0.15)
				(type solid)
			)
			(layer "B.Fab")
		)
		(fp_line
			(start -0.494 0.25)
			(end 0.504 0.25)
			(stroke
				(width 0.15)
				(type solid)
			)
			(layer "B.Fab")
		)
		(fp_line
			(start 0.504 -0.248)
			(end -0.494 -0.248)
			(stroke
				(width 0.15)
				(type solid)
			)
			(layer "B.Fab")
		)
		(fp_line
			(start 0.504 0.25)
			(end 0.504 -0.248)
			(stroke
				(width 0.15)
				(type solid)
			)
			(layer "B.Fab")
		)
		(pad "1" smd roundrect
			(at -0.48 0)
			(size 0.59 0.64)
			(layers "B.Cu" "B.Mask" "B.Paste")
			(roundrect_rratio 0.25)
			(net 28 "GND")
			(pintype "passive")
		)
		(pad "2" smd roundrect
			(at 0.48 0)
			(size 0.59 0.64)
			(layers "B.Cu" "B.Mask" "B.Paste")
			(roundrect_rratio 0.25)
			(net 299 "/2xRJ45/P0_CT")
			(pintype "passive")
		)
	)
	(footprint "antmicro-footprints:C_0402_1005Metric"
		(layer "B.Cu")
		(at 90.225 100.15 90)
		(descr "Capacitor SMD 0402")
		(tags "capacitor SMD 0402")
		(property "Reference" "C87"
			(at 9.87 -0.388176 90)
			(layer "B.SilkS")
			(effects
				(font
					(size 0.7 0.7)
					(thickness 0.15)
				)
				(justify right top mirror)
			)
		)
		(property "Value" "C_1u_25V_0402"
			(at -1.022927 -2.155213 90)
			(layer "B.Fab")
			(hide yes)
			(effects
				(font
					(size 0.7 0.7)
					(thickness 0.15)
				)
				(justify right top mirror)
			)
		)
		(property "Datasheet" "https://www.murata.com/products/productdetail?partno=GRM155R61E105KE11%23"
			(at 0 0 90)
			(layer "B.Fab")
			(hide yes)
			(effects
				(font
					(size 1.27 1.27)
					(thickness 0.15)
				)
				(justify mirror)
			)
		)
		(property "Description" "SMD Multilayer Ceramic Capacitor, 1 µF, 25 V, 0402 [1005 Metric], ± 10%, X5R, GRM Series"
			(at 0 0 90)
			(layer "B.Fab")
			(hide yes)
			(effects
				(font
					(size 1.27 1.27)
					(thickness 0.15)
				)
				(justify mirror)
			)
		)
		(property "MPN" "GRM155R61E105KE11J"
			(at 0 0 90)
			(unlocked yes)
			(layer "B.Fab")
			(hide yes)
			(effects
				(font
					(size 1 1)
					(thickness 0.15)
				)
				(justify mirror)
			)
		)
		(property "Manufacturer" "Murata"
			(at 0 0 90)
			(unlocked yes)
			(layer "B.Fab")
			(hide yes)
			(effects
				(font
					(size 1 1)
					(thickness 0.15)
				)
				(justify mirror)
			)
		)
		(property "License" "Apache-2.0"
			(at 0 0 90)
			(unlocked yes)
			(layer "B.Fab")
			(hide yes)
			(effects
				(font
					(size 1 1)
					(thickness 0.15)
				)
				(justify mirror)
			)
		)
		(property "Author" "Antmicro"
			(at 0 0 90)
			(unlocked yes)
			(layer "B.Fab")
			(hide yes)
			(effects
				(font
					(size 1 1)
					(thickness 0.15)
				)
				(justify mirror)
			)
		)
		(property "Val" "1u"
			(at 0 0 90)
			(unlocked yes)
			(layer "B.Fab")
			(hide yes)
			(effects
				(font
					(size 1 1)
					(thickness 0.15)
				)
				(justify mirror)
			)
		)
		(property "Voltage" "25V"
			(at 0 0 90)
			(unlocked yes)
			(layer "B.Fab")
			(hide yes)
			(effects
				(font
					(size 1 1)
					(thickness 0.15)
				)
				(justify mirror)
			)
		)
		(property "Dielectric" "X5R"
			(at 0 0 90)
			(unlocked yes)
			(layer "B.Fab")
			(hide yes)
			(effects
				(font
					(size 1 1)
					(thickness 0.15)
				)
				(justify mirror)
			)
		)
		(sheetname "/X710-AT2 power/")
		(sheetfile "x710-at2-power.kicad_sch")
		(attr smd)
		(fp_rect
			(start -0.925 0.47)
			(end 0.925 -0.47)
			(stroke
				(width 0.05)
				(type default)
			)
			(fill no)
			(layer "B.CrtYd")
		)
		(fp_line
			(start 0.504 -0.248)
			(end -0.494 -0.248)
			(stroke
				(width 0.15)
				(type solid)
			)
			(layer "B.Fab")
		)
		(fp_line
			(start -0.494 -0.248)
			(end -0.494 0.25)
			(stroke
				(width 0.15)
				(type solid)
			)
			(layer "B.Fab")
		)
		(fp_line
			(start 0.504 0.25)
			(end 0.504 -0.248)
			(stroke
				(width 0.15)
				(type solid)
			)
			(layer "B.Fab")
		)
		(fp_line
			(start -0.494 0.25)
			(end 0.504 0.25)
			(stroke
				(width 0.15)
				(type solid)
			)
			(layer "B.Fab")
		)
		(pad "1" smd roundrect
			(at -0.48 0 90)
			(size 0.59 0.64)
			(layers "B.Cu" "B.Mask" "B.Paste")
			(roundrect_rratio 0.25)
			(net 28 "GND")
			(pintype "passive")
		)
		(pad "2" smd roundrect
			(at 0.48 0 90)
			(size 0.59 0.64)
			(layers "B.Cu" "B.Mask" "B.Paste")
			(roundrect_rratio 0.25)
			(net 1 "VCCA")
			(pintype "passive")
		)
	)
	(footprint "antmicro-footprints:C_0402_1005Metric"
		(layer "B.Cu")
		(at 88 132.4)
		(descr "Capacitor SMD 0402")
		(tags "capacitor SMD 0402")
		(property "Reference" "C66"
			(at -0.98 2.59 0)
			(layer "B.SilkS")
			(effects
				(font
					(size 0.7 0.7)
					(thickness 0.15)
				)
				(justify right top mirror)
			)
		)
		(property "Value" "C_1u_25V_0402"
			(at -1.022927 -2.155213 0)
			(layer "B.Fab")
			(hide yes)
			(effects
				(font
					(size 0.7 0.7)
					(thickness 0.15)
				)
				(justify right top mirror)
			)
		)
		(property "Datasheet" "https://www.murata.com/products/productdetail?partno=GRM155R61E105KE11%23"
			(at 0 0 0)
			(layer "B.Fab")
			(hide yes)
			(effects
				(font
					(size 1.27 1.27)
					(thickness 0.15)
				)
				(justify mirror)
			)
		)
		(property "Description" "SMD Multilayer Ceramic Capacitor, 1 µF, 25 V, 0402 [1005 Metric], ± 10%, X5R, GRM Series"
			(at 0 0 0)
			(layer "B.Fab")
			(hide yes)
			(effects
				(font
					(size 1.27 1.27)
					(thickness 0.15)
				)
				(justify mirror)
			)
		)
		(property "MPN" "GRM155R61E105KE11J"
			(at 0 0 0)
			(unlocked yes)
			(layer "B.Fab")
			(hide yes)
			(effects
				(font
					(size 1 1)
					(thickness 0.15)
				)
				(justify mirror)
			)
		)
		(property "Manufacturer" "Murata"
			(at 0 0 0)
			(unlocked yes)
			(layer "B.Fab")
			(hide yes)
			(effects
				(font
					(size 1 1)
					(thickness 0.15)
				)
				(justify mirror)
			)
		)
		(property "License" "Apache-2.0"
			(at 0 0 0)
			(unlocked yes)
			(layer "B.Fab")
			(hide yes)
			(effects
				(font
					(size 1 1)
					(thickness 0.15)
				)
				(justify mirror)
			)
		)
		(property "Author" "Antmicro"
			(at 0 0 0)
			(unlocked yes)
			(layer "B.Fab")
			(hide yes)
			(effects
				(font
					(size 1 1)
					(thickness 0.15)
				)
				(justify mirror)
			)
		)
		(property "Val" "1u"
			(at 0 0 0)
			(unlocked yes)
			(layer "B.Fab")
			(hide yes)
			(effects
				(font
					(size 1 1)
					(thickness 0.15)
				)
				(justify mirror)
			)
		)
		(property "Voltage" "25V"
			(at 0 0 0)
			(unlocked yes)
			(layer "B.Fab")
			(hide yes)
			(effects
				(font
					(size 1 1)
					(thickness 0.15)
				)
				(justify mirror)
			)
		)
		(property "Dielectric" "X5R"
			(at 0 0 0)
			(unlocked yes)
			(layer "B.Fab")
			(hide yes)
			(effects
				(font
					(size 1 1)
					(thickness 0.15)
				)
				(justify mirror)
			)
		)
		(sheetname "/2xRJ45/")
		(sheetfile "2xrj45.kicad_sch")
		(attr smd)
		(fp_rect
			(start -0.925 0.47)
			(end 0.925 -0.47)
			(stroke
				(width 0.05)
				(type default)
			)
			(fill no)
			(layer "B.CrtYd")
		)
		(fp_line
			(start -0.494 -0.248)
			(end -0.494 0.25)
			(stroke
				(width 0.15)
				(type solid)
			)
			(layer "B.Fab")
		)
		(fp_line
			(start -0.494 0.25)
			(end 0.504 0.25)
			(stroke
				(width 0.15)
				(type solid)
			)
			(layer "B.Fab")
		)
		(fp_line
			(start 0.504 -0.248)
			(end -0.494 -0.248)
			(stroke
				(width 0.15)
				(type solid)
			)
			(layer "B.Fab")
		)
		(fp_line
			(start 0.504 0.25)
			(end 0.504 -0.248)
			(stroke
				(width 0.15)
				(type solid)
			)
			(layer "B.Fab")
		)
		(pad "1" smd roundrect
			(at -0.48 0)
			(size 0.59 0.64)
			(layers "B.Cu" "B.Mask" "B.Paste")
			(roundrect_rratio 0.25)
			(net 28 "GND")
			(pintype "passive")
		)
		(pad "2" smd roundrect
			(at 0.48 0)
			(size 0.59 0.64)
			(layers "B.Cu" "B.Mask" "B.Paste")
			(roundrect_rratio 0.25)
			(net 300 "/2xRJ45/P1_CT")
			(pintype "passive")
		)
	)
	(footprint "antmicro-footprints:C_0402_1005Metric"
		(layer "B.Cu")
		(at 96.88 112.960001)
		(descr "Capacitor SMD 0402")
		(tags "capacitor SMD 0402")
		(property "Reference" "C74"
			(at -2.9 -0.290001 0)
			(layer "B.SilkS")
			(effects
				(font
					(size 0.7 0.7)
					(thickness 0.15)
				)
				(justify right top mirror)
			)
		)
		(property "Value" "C_100n_0402"
			(at -1.022927 -2.155213 0)
			(layer "B.Fab")
			(hide yes)
			(effects
				(font
					(size 0.7 0.7)
					(thickness 0.15)
				)
				(justify right top mirror)
			)
		)
		(property "Datasheet" "https://www.murata.com/products/productdetail?partno=GRM155R61H104KE14%23"
			(at 0 0 0)
			(layer "B.Fab")
			(hide yes)
			(effects
				(font
					(size 1.27 1.27)
					(thickness 0.15)
				)
				(justify mirror)
			)
		)
		(property "Description" "SMD Multilayer Ceramic Capacitor, 0.1 µF, 50 V, 0402 [1005 Metric], ± 10%, X5R, GRM Series"
			(at 0 0 0)
			(layer "B.Fab")
			(hide yes)
			(effects
				(font
					(size 1.27 1.27)
					(thickness 0.15)
				)
				(justify mirror)
			)
		)
		(property "MPN" "GRM155R61H104KE14D"
			(at 0 0 0)
			(unlocked yes)
			(layer "B.Fab")
			(hide yes)
			(effects
				(font
					(size 1 1)
					(thickness 0.15)
				)
				(justify mirror)
			)
		)
		(property "Val" "100n"
			(at 0 0 0)
			(unlocked yes)
			(layer "B.Fab")
			(hide yes)
			(effects
				(font
					(size 1 1)
					(thickness 0.15)
				)
				(justify mirror)
			)
		)
		(property "Voltage" "50V"
			(at 0 0 0)
			(unlocked yes)
			(layer "B.Fab")
			(hide yes)
			(effects
				(font
					(size 1 1)
					(thickness 0.15)
				)
				(justify mirror)
			)
		)
		(property "Dielectric" "X5R"
			(at 0 0 0)
			(unlocked yes)
			(layer "B.Fab")
			(hide yes)
			(effects
				(font
					(size 1 1)
					(thickness 0.15)
				)
				(justify mirror)
			)
		)
		(property "Manufacturer" "Murata"
			(at 0 0 0)
			(unlocked yes)
			(layer "B.Fab")
			(hide yes)
			(effects
				(font
					(size 1 1)
					(thickness 0.15)
				)
				(justify mirror)
			)
		)
		(property "License" "Apache-2.0"
			(at 0 0 0)
			(unlocked yes)
			(layer "B.Fab")
			(hide yes)
			(effects
				(font
					(size 1 1)
					(thickness 0.15)
				)
				(justify mirror)
			)
		)
		(property "Author" "Antmicro"
			(at 0 0 0)
			(unlocked yes)
			(layer "B.Fab")
			(hide yes)
			(effects
				(font
					(size 1 1)
					(thickness 0.15)
				)
				(justify mirror)
			)
		)
		(sheetname "/X710-AT2 Misc/")
		(sheetfile "x710-at2-mics.kicad_sch")
		(attr smd)
		(fp_rect
			(start -0.925 0.47)
			(end 0.925 -0.47)
			(stroke
				(width 0.05)
				(type default)
			)
			(fill no)
			(layer "B.CrtYd")
		)
		(fp_line
			(start -0.494 -0.248)
			(end -0.494 0.25)
			(stroke
				(width 0.15)
				(type solid)
			)
			(layer "B.Fab")
		)
		(fp_line
			(start -0.494 0.25)
			(end 0.504 0.25)
			(stroke
				(width 0.15)
				(type solid)
			)
			(layer "B.Fab")
		)
		(fp_line
			(start 0.504 -0.248)
			(end -0.494 -0.248)
			(stroke
				(width 0.15)
				(type solid)
			)
			(layer "B.Fab")
		)
		(fp_line
			(start 0.504 0.25)
			(end 0.504 -0.248)
			(stroke
				(width 0.15)
				(type solid)
			)
			(layer "B.Fab")
		)
		(pad "1" smd roundrect
			(at -0.48 0)
			(size 0.59 0.64)
			(layers "B.Cu" "B.Mask" "B.Paste")
			(roundrect_rratio 0.25)
			(net 28 "GND")
			(pintype "passive")
		)
		(pad "2" smd roundrect
			(at 0.48 0)
			(size 0.59 0.64)
			(layers "B.Cu" "B.Mask" "B.Paste")
			(roundrect_rratio 0.25)
			(net 18 "+1V88")
			(pintype "passive")
		)
	)
)
